(kicad_pcb
	(version 20241229)
	(generator "pcbnew")
	(generator_version "9.0")
	(general
		(thickness 1.711)
		(legacy_teardrops no)
	)
	(paper "A4")
	(title_block
		(title "Antmicro Baseboard for Jetson AGX Thor")
		(date "2026-02-18")
		(rev "1.1.0")
		(company "Antmicro Ltd")
		(comment 1 "www.antmicro.com")
		(comment 9 "footprints 492-495 of 1170")
	)
	(layers
		(0 "F.Cu" signal)
		(4 "In1.Cu" signal)
		(6 "In2.Cu" signal)
		(8 "In3.Cu" signal)
		(10 "In4.Cu" jumper)
		(12 "In5.Cu" signal)
		(14 "In6.Cu" signal)
		(16 "In7.Cu" signal)
		(18 "In8.Cu" signal)
		(2 "B.Cu" signal)
		(9 "F.Adhes" user "F.Adhesive")
		(11 "B.Adhes" user "B.Adhesive")
		(13 "F.Paste" user)
		(15 "B.Paste" user)
		(5 "F.SilkS" user "F.Silkscreen")
		(7 "B.SilkS" user "B.Silkscreen")
		(1 "F.Mask" user)
		(3 "B.Mask" user)
		(17 "Dwgs.User" user "User.Drawings")
		(19 "Cmts.User" user "User.Comments")
		(21 "Eco1.User" user "User.Eco1")
		(23 "Eco2.User" user "User.Eco2")
		(25 "Edge.Cuts" user)
		(27 "Margin" user)
		(31 "F.CrtYd" user "F.Courtyard")
		(29 "B.CrtYd" user "B.Courtyard")
		(35 "F.Fab" user)
		(33 "B.Fab" user)
	)
	(footprint "antmicro-footprints:LED_0603_1608Metric_G"
		(layer "F.Cu")
		(at 172.1 63.2 -90)
		(descr "LED SMD 0603 Green")
		(tags "LED SMD 0603 Green")
		(property "Reference" "D36"
			(at -0.89 -1.72 90)
			(layer "F.SilkS")
			(effects
				(font
					(size 0.7 0.7)
					(thickness 0.15)
				)
				(justify right top)
			)
		)
		(property "Value" "LED_G_0603_LTST-C190GKT"
			(at -0.001 1.599 90)
			(layer "F.Fab")
			(effects
				(font
					(size 0.7 0.7)
					(thickness 0.15)
				)
				(justify right top)
			)
		)
		(property "Datasheet" "https://media.digikey.com/pdf/Data%20Sheets/Lite-On%20PDFs/LTST-C190GKT.pdf"
			(at 0 0 90)
			(layer "F.Fab")
			(hide yes)
			(effects
				(font
					(size 1.27 1.27)
					(thickness 0.15)
				)
			)
		)
		(property "Description" "LED, Green, SMD, 0603, 20 mA, 2.1 V, 569 nm"
			(at 0 0 90)
			(layer "F.Fab")
			(hide yes)
			(effects
				(font
					(size 1.27 1.27)
					(thickness 0.15)
				)
			)
		)
		(property "MPN" "LTST-C190GKT"
			(at 0 0 270)
			(unlocked yes)
			(layer "F.Fab")
			(hide yes)
			(effects
				(font
					(size 1 1)
					(thickness 0.15)
				)
			)
		)
		(property "Manufacturer" "Lite-On"
			(at 0 0 270)
			(unlocked yes)
			(layer "F.Fab")
			(hide yes)
			(effects
				(font
					(size 1 1)
					(thickness 0.15)
				)
			)
		)
		(property "Author" "Antmicro"
			(at 0 0 270)
			(unlocked yes)
			(layer "F.Fab")
			(hide yes)
			(effects
				(font
					(size 1 1)
					(thickness 0.15)
				)
			)
		)
		(property "License" "Apache-2.0"
			(at 0 0 270)
			(unlocked yes)
			(layer "F.Fab")
			(hide yes)
			(effects
				(font
					(size 1 1)
					(thickness 0.15)
				)
			)
		)
		(property "Color" "Green"
			(at 0 0 270)
			(unlocked yes)
			(layer "F.Fab")
			(hide yes)
			(effects
				(font
					(size 1 1)
					(thickness 0.15)
				)
			)
		)
		(sheetname "/Peripherals/")
		(sheetfile "peripherals.kicad_sch")
		(attr smd)
		(fp_line
			(start 0.22 0.35)
			(end -0.22 0.35)
			(stroke
				(width 0.15)
				(type solid)
			)
			(layer "F.SilkS")
		)
		(fp_line
			(start -0.094672 0.201008)
			(end -0.094672 -0.198992)
			(stroke
				(width 0.1)
				(type solid)
			)
			(layer "F.SilkS")
		)
		(fp_line
			(start 0.105328 0.201008)
			(end -0.094672 0.001008)
			(stroke
				(width 0.1)
				(type solid)
			)
			(layer "F.SilkS")
		)
		(fp_line
			(start 0.105328 0.201008)
			(end 0.105328 -0.198992)
			(stroke
				(width 0.1)
				(type solid)
			)
			(layer "F.SilkS")
		)
		(fp_line
			(start -0.094672 0.001008)
			(end -0.24 0.001008)
			(stroke
				(width 0.1)
				(type solid)
			)
			(layer "F.SilkS")
		)
		(fp_line
			(start -0.094672 0.001008)
			(end 0.105328 -0.198992)
			(stroke
				(width 0.1)
				(type solid)
			)
			(layer "F.SilkS")
		)
		(fp_line
			(start 0.105328 0.001008)
			(end 0.24 0.001)
			(stroke
				(width 0.1)
				(type solid)
			)
			(layer "F.SilkS")
		)
		(fp_line
			(start -1.18 -0.319)
			(end -1.18 0.321)
			(stroke
				(width 0.15)
				(type solid)
			)
			(layer "F.SilkS")
		)
		(fp_line
			(start 0.22 -0.35)
			(end -0.22 -0.35)
			(stroke
				(width 0.15)
				(type solid)
			)
			(layer "F.SilkS")
		)
		(fp_rect
			(start 1.25 0.65)
			(end -1.25 -0.65)
			(stroke
				(width 0.05)
				(type solid)
			)
			(fill no)
			(layer "F.CrtYd")
		)
		(fp_line
			(start -0.199 0.2)
			(end -0.199 0.1)
			(stroke
				(width 0.15)
				(type solid)
			)
			(layer "F.Fab")
		)
		(fp_line
			(start 0.201 0.2)
			(end 0.201 0)
			(stroke
				(width 0.15)
				(type solid)
			)
			(layer "F.Fab")
		)
		(fp_line
			(start -0.199 0)
			(end -0.597 0)
			(stroke
				(width 0.15)
				(type solid)
			)
			(layer "F.Fab")
		)
		(fp_line
			(start -0.101 0)
			(end 0.201 0.2)
			(stroke
				(width 0.15)
				(type solid)
			)
			(layer "F.Fab")
		)
		(fp_line
			(start 0.201 0)
			(end 0.201 -0.202)
			(stroke
				(width 0.15)
				(type solid)
			)
			(layer "F.Fab")
		)
		(fp_line
			(start 0.599 0)
			(end 0.201 0)
			(stroke
				(width 0.15)
				(type solid)
			)
			(layer "F.Fab")
		)
		(fp_line
			(start -0.199 -0.202)
			(end -0.199 0.1)
			(stroke
				(width 0.15)
				(type solid)
			)
			(layer "F.Fab")
		)
		(fp_line
			(start 0.201 -0.202)
			(end -0.101 0)
			(stroke
				(width 0.15)
				(type solid)
			)
			(layer "F.Fab")
		)
		(fp_rect
			(start 0.848 0.4)
			(end -0.85 -0.402)
			(stroke
				(width 0.15)
				(type solid)
			)
			(fill no)
			(layer "F.Fab")
		)
		(fp_text user "License: Apache-2.0"
			(at -1.4224 3.599 90)
			(layer "F.Fab")
			(effects
				(font
					(size 0.7 0.7)
					(thickness 0.15)
				)
				(justify right top)
			)
		)
		(fp_text user "Author: Antmicro"
			(at -1.4224 4.799 90)
			(layer "F.Fab")
			(effects
				(font
					(size 0.7 0.7)
					(thickness 0.15)
				)
				(justify right top)
			)
		)
		(fp_text user "${REFERENCE}"
			(at -1.4224 5.999 90)
			(layer "F.Fab")
			(effects
				(font
					(size 0.7 0.7)
					(thickness 0.15)
				)
				(justify right top)
			)
		)
		(pad "1" smd roundrect
			(at -0.7 0 90)
			(size 0.8 1)
			(layers "F.Cu" "F.Mask" "F.Paste")
			(roundrect_rratio 0.2)
			(net 39 "Net-(D36-C)")
			(pinfunction "C")
			(pintype "passive")
		)
		(pad "2" smd roundrect
			(at 0.7 0 90)
			(size 0.8 1)
			(layers "F.Cu" "F.Mask" "F.Paste")
			(roundrect_rratio 0.2)
			(net 38 "Net-(D36-A)")
			(pinfunction "A")
			(pintype "passive")
		)
	)
	(footprint "antmicro-footprints:LED_0603_1608Metric_G"
		(layer "F.Cu")
		(at 169.98 63.2 -90)
		(descr "LED SMD 0603 Green")
		(tags "LED SMD 0603 Green")
		(property "Reference" "D35"
			(at -0.9 2.58 90)
			(layer "F.SilkS")
			(effects
				(font
					(size 0.7 0.7)
					(thickness 0.15)
				)
				(justify right top)
			)
		)
		(property "Value" "LED_G_0603_LTST-C190GKT"
			(at -0.001 1.599 90)
			(layer "F.Fab")
			(effects
				(font
					(size 0.7 0.7)
					(thickness 0.15)
				)
				(justify right top)
			)
		)
		(property "Datasheet" "https://media.digikey.com/pdf/Data%20Sheets/Lite-On%20PDFs/LTST-C190GKT.pdf"
			(at 0 0 90)
			(layer "F.Fab")
			(hide yes)
			(effects
				(font
					(size 1.27 1.27)
					(thickness 0.15)
				)
			)
		)
		(property "Description" "LED, Green, SMD, 0603, 20 mA, 2.1 V, 569 nm"
			(at 0 0 90)
			(layer "F.Fab")
			(hide yes)
			(effects
				(font
					(size 1.27 1.27)
					(thickness 0.15)
				)
			)
		)
		(property "MPN" "LTST-C190GKT"
			(at 0 0 270)
			(unlocked yes)
			(layer "F.Fab")
			(hide yes)
			(effects
				(font
					(size 1 1)
					(thickness 0.15)
				)
			)
		)
		(property "Manufacturer" "Lite-On"
			(at 0 0 270)
			(unlocked yes)
			(layer "F.Fab")
			(hide yes)
			(effects
				(font
					(size 1 1)
					(thickness 0.15)
				)
			)
		)
		(property "Author" "Antmicro"
			(at 0 0 270)
			(unlocked yes)
			(layer "F.Fab")
			(hide yes)
			(effects
				(font
					(size 1 1)
					(thickness 0.15)
				)
			)
		)
		(property "License" "Apache-2.0"
			(at 0 0 270)
			(unlocked yes)
			(layer "F.Fab")
			(hide yes)
			(effects
				(font
					(size 1 1)
					(thickness 0.15)
				)
			)
		)
		(property "Color" "Green"
			(at 0 0 270)
			(unlocked yes)
			(layer "F.Fab")
			(hide yes)
			(effects
				(font
					(size 1 1)
					(thickness 0.15)
				)
			)
		)
		(sheetname "/Peripherals/")
		(sheetfile "peripherals.kicad_sch")
		(attr smd)
		(fp_line
			(start 0.22 0.35)
			(end -0.22 0.35)
			(stroke
				(width 0.15)
				(type solid)
			)
			(layer "F.SilkS")
		)
		(fp_line
			(start -0.094672 0.201008)
			(end -0.094672 -0.198992)
			(stroke
				(width 0.1)
				(type solid)
			)
			(layer "F.SilkS")
		)
		(fp_line
			(start 0.105328 0.201008)
			(end -0.094672 0.001008)
			(stroke
				(width 0.1)
				(type solid)
			)
			(layer "F.SilkS")
		)
		(fp_line
			(start 0.105328 0.201008)
			(end 0.105328 -0.198992)
			(stroke
				(width 0.1)
				(type solid)
			)
			(layer "F.SilkS")
		)
		(fp_line
			(start -0.094672 0.001008)
			(end -0.24 0.001008)
			(stroke
				(width 0.1)
				(type solid)
			)
			(layer "F.SilkS")
		)
		(fp_line
			(start -0.094672 0.001008)
			(end 0.105328 -0.198992)
			(stroke
				(width 0.1)
				(type solid)
			)
			(layer "F.SilkS")
		)
		(fp_line
			(start 0.105328 0.001008)
			(end 0.24 0.001)
			(stroke
				(width 0.1)
				(type solid)
			)
			(layer "F.SilkS")
		)
		(fp_line
			(start -1.18 -0.319)
			(end -1.18 0.321)
			(stroke
				(width 0.15)
				(type solid)
			)
			(layer "F.SilkS")
		)
		(fp_line
			(start 0.22 -0.35)
			(end -0.22 -0.35)
			(stroke
				(width 0.15)
				(type solid)
			)
			(layer "F.SilkS")
		)
		(fp_rect
			(start 1.25 0.65)
			(end -1.25 -0.65)
			(stroke
				(width 0.05)
				(type solid)
			)
			(fill no)
			(layer "F.CrtYd")
		)
		(fp_line
			(start -0.199 0.2)
			(end -0.199 0.1)
			(stroke
				(width 0.15)
				(type solid)
			)
			(layer "F.Fab")
		)
		(fp_line
			(start 0.201 0.2)
			(end 0.201 0)
			(stroke
				(width 0.15)
				(type solid)
			)
			(layer "F.Fab")
		)
		(fp_line
			(start -0.199 0)
			(end -0.597 0)
			(stroke
				(width 0.15)
				(type solid)
			)
			(layer "F.Fab")
		)
		(fp_line
			(start -0.101 0)
			(end 0.201 0.2)
			(stroke
				(width 0.15)
				(type solid)
			)
			(layer "F.Fab")
		)
		(fp_line
			(start 0.201 0)
			(end 0.201 -0.202)
			(stroke
				(width 0.15)
				(type solid)
			)
			(layer "F.Fab")
		)
		(fp_line
			(start 0.599 0)
			(end 0.201 0)
			(stroke
				(width 0.15)
				(type solid)
			)
			(layer "F.Fab")
		)
		(fp_line
			(start -0.199 -0.202)
			(end -0.199 0.1)
			(stroke
				(width 0.15)
				(type solid)
			)
			(layer "F.Fab")
		)
		(fp_line
			(start 0.201 -0.202)
			(end -0.101 0)
			(stroke
				(width 0.15)
				(type solid)
			)
			(layer "F.Fab")
		)
		(fp_rect
			(start 0.848 0.4)
			(end -0.85 -0.402)
			(stroke
				(width 0.15)
				(type solid)
			)
			(fill no)
			(layer "F.Fab")
		)
		(fp_text user "${REFERENCE}"
			(at -1.4224 5.999 90)
			(layer "F.Fab")
			(effects
				(font
					(size 0.7 0.7)
					(thickness 0.15)
				)
				(justify right top)
			)
		)
		(fp_text user "License: Apache-2.0"
			(at -1.4224 3.599 90)
			(layer "F.Fab")
			(effects
				(font
					(size 0.7 0.7)
					(thickness 0.15)
				)
				(justify right top)
			)
		)
		(fp_text user "Author: Antmicro"
			(at -1.4224 4.799 90)
			(layer "F.Fab")
			(effects
				(font
					(size 0.7 0.7)
					(thickness 0.15)
				)
				(justify right top)
			)
		)
		(pad "1" smd roundrect
			(at -0.7 0 90)
			(size 0.8 1)
			(layers "F.Cu" "F.Mask" "F.Paste")
			(roundrect_rratio 0.2)
			(net 37 "Net-(D35-C)")
			(pinfunction "C")
			(pintype "passive")
		)
		(pad "2" smd roundrect
			(at 0.7 0 90)
			(size 0.8 1)
			(layers "F.Cu" "F.Mask" "F.Paste")
			(roundrect_rratio 0.2)
			(net 36 "Net-(D35-A)")
			(pinfunction "A")
			(pintype "passive")
		)
	)
	(footprint "antmicro-footprints:C_0402_1005Metric"
		(layer "F.Cu")
		(at 160.368936 99.565 180)
		(descr "Capacitor SMD 0402")
		(tags "capacitor SMD 0402")
		(property "Reference" "C36"
			(at 3.968936 0.365 0)
			(layer "F.SilkS")
			(effects
				(font
					(size 0.7 0.7)
					(thickness 0.15)
				)
				(justify right top)
			)
		)
		(property "Value" "C_100n_0402"
			(at -1.022927 2.155213 0)
			(layer "F.Fab")
			(effects
				(font
					(size 0.7 0.7)
					(thickness 0.15)
				)
				(justify right top)
			)
		)
		(property "Datasheet" "https://www.murata.com/products/productdetail?partno=GRM155R61H104KE14%23"
			(at 0 0 0)
			(layer "F.Fab")
			(hide yes)
			(effects
				(font
					(size 1.27 1.27)
					(thickness 0.15)
				)
			)
		)
		(property "Description" "SMD Multilayer Ceramic Capacitor, 0.1 µF, 50 V, 0402 [1005 Metric], ± 10%, X5R, GRM Series"
			(at 0 0 0)
			(layer "F.Fab")
			(hide yes)
			(effects
				(font
					(size 1.27 1.27)
					(thickness 0.15)
				)
			)
		)
		(property "MPN" "GRM155R61H104KE14D"
			(at 0 0 180)
			(unlocked yes)
			(layer "F.Fab")
			(hide yes)
			(effects
				(font
					(size 1 1)
					(thickness 0.15)
				)
			)
		)
		(property "Manufacturer" "Murata"
			(at 0 0 180)
			(unlocked yes)
			(layer "F.Fab")
			(hide yes)
			(effects
				(font
					(size 1 1)
					(thickness 0.15)
				)
			)
		)
		(property "License" "Apache-2.0"
			(at 0 0 180)
			(unlocked yes)
			(layer "F.Fab")
			(hide yes)
			(effects
				(font
					(size 1 1)
					(thickness 0.15)
				)
			)
		)
		(property "Author" "Antmicro"
			(at 0 0 180)
			(unlocked yes)
			(layer "F.Fab")
			(hide yes)
			(effects
				(font
					(size 1 1)
					(thickness 0.15)
				)
			)
		)
		(property "Val" "100n"
			(at 0 0 180)
			(unlocked yes)
			(layer "F.Fab")
			(hide yes)
			(effects
				(font
					(size 1 1)
					(thickness 0.15)
				)
			)
		)
		(property "Voltage" "50V"
			(at 0 0 180)
			(unlocked yes)
			(layer "F.Fab")
			(hide yes)
			(effects
				(font
					(size 1 1)
					(thickness 0.15)
				)
			)
		)
		(property "Dielectric" "X5R"
			(at 0 0 180)
			(unlocked yes)
			(layer "F.Fab")
			(hide yes)
			(effects
				(font
					(size 1 1)
					(thickness 0.15)
				)
			)
		)
		(property "Public" "False"
			(at 0 0 180)
			(unlocked yes)
			(layer "F.Fab")
			(hide yes)
			(effects
				(font
					(size 1 1)
					(thickness 0.15)
				)
			)
		)
		(component_classes
			(class "DCDC_SOM")
		)
		(sheetname "/DCDC/")
		(sheetfile "dcdc.kicad_sch")
		(attr smd)
		(fp_rect
			(start -0.925 -0.47)
			(end 0.925 0.47)
			(stroke
				(width 0.05)
				(type default)
			)
			(fill no)
			(layer "F.CrtYd")
		)
		(fp_line
			(start 0.504 0.248)
			(end -0.494 0.248)
			(stroke
				(width 0.15)
				(type solid)
			)
			(layer "F.Fab")
		)
		(fp_line
			(start 0.504 -0.25)
			(end 0.504 0.248)
			(stroke
				(width 0.15)
				(type solid)
			)
			(layer "F.Fab")
		)
		(fp_line
			(start -0.494 0.248)
			(end -0.494 -0.25)
			(stroke
				(width 0.15)
				(type solid)
			)
			(layer "F.Fab")
		)
		(fp_line
			(start -0.494 -0.25)
			(end 0.504 -0.25)
			(stroke
				(width 0.15)
				(type solid)
			)
			(layer "F.Fab")
		)
		(fp_text user "Author: Antmicro"
			(at -0.939 3.399 0)
			(layer "F.Fab")
			(effects
				(font
					(size 0.7 0.7)
					(thickness 0.15)
				)
				(justify right top)
			)
		)
		(fp_text user "${REFERENCE}"
			(at -0.939 4.599 0)
			(layer "F.Fab")
			(effects
				(font
					(size 0.7 0.7)
					(thickness 0.15)
				)
				(justify right top)
			)
		)
		(fp_text user "License: Apache-2.0"
			(at -0.939 5.799 0)
			(layer "F.Fab")
			(effects
				(font
					(size 0.7 0.7)
					(thickness 0.15)
				)
				(justify right top)
			)
		)
		(pad "1" smd roundrect
			(at -0.48 0 180)
			(size 0.59 0.64)
			(layers "F.Cu" "F.Mask" "F.Paste")
			(roundrect_rratio 0.25)
			(net 1 "GND")
			(pintype "passive")
		)
		(pad "2" smd roundrect
			(at 0.48 0 180)
			(size 0.59 0.64)
			(layers "F.Cu" "F.Mask" "F.Paste")
			(roundrect_rratio 0.25)
			(net 4 "+3V3_AON")
			(pintype "passive")
		)
	)
	(footprint "antmicro-footprints:R_0402_1005Metric"
		(layer "F.Cu")
		(at 64.25 85.95 -90)
		(descr "Resistor SMD 0402")
		(tags "resistor SMD 0402")
		(property "Reference" "R168"
			(at -3.85 0.35 90)
			(layer "F.SilkS")
			(effects
				(font
					(size 0.7 0.7)
					(thickness 0.15)
				)
				(justify right top)
			)
		)
		(property "Value" "R_10k_0402"
			(at -1.011843 1.772047 90)
			(layer "F.Fab")
			(effects
				(font
					(size 0.7 0.7)
					(thickness 0.15)
				)
				(justify right top)
			)
		)
		(property "Datasheet" "https://www.bourns.com/docs/product-datasheets/cr.pdf"
			(at 0 0 90)
			(layer "F.Fab")
			(hide yes)
			(effects
				(font
					(size 1.27 1.27)
					(thickness 0.15)
				)
			)
		)
		(property "Description" "SMD Chip Resistor, 10 kohm, ± 1%, 62.5 mW, 0402 [1005 Metric], Thick Film, General Purpose"
			(at 0 0 90)
			(layer "F.Fab")
			(hide yes)
			(effects
				(font
					(size 1.27 1.27)
					(thickness 0.15)
				)
			)
		)
		(property "Manufacturer" "Bourns"
			(at 0 0 270)
			(unlocked yes)
			(layer "F.Fab")
			(hide yes)
			(effects
				(font
					(size 1 1)
					(thickness 0.15)
				)
			)
		)
		(property "MPN" "CR0402-FX-1002GLF"
			(at 0 0 270)
			(unlocked yes)
			(layer "F.Fab")
			(hide yes)
			(effects
				(font
					(size 1 1)
					(thickness 0.15)
				)
			)
		)
		(property "Val" "10k"
			(at 0 0 270)
			(unlocked yes)
			(layer "F.Fab")
			(hide yes)
			(effects
				(font
					(size 1 1)
					(thickness 0.15)
				)
			)
		)
		(property "License" "Apache-2.0"
			(at 0 0 270)
			(unlocked yes)
			(layer "F.Fab")
			(hide yes)
			(effects
				(font
					(size 1 1)
					(thickness 0.15)
				)
			)
		)
		(property "Author" "Antmicro"
			(at 0 0 270)
			(unlocked yes)
			(layer "F.Fab")
			(hide yes)
			(effects
				(font
					(size 1 1)
					(thickness 0.15)
				)
			)
		)
		(property "Tolerance" "1%"
			(at 0 0 270)
			(unlocked yes)
			(layer "F.Fab")
			(hide yes)
			(effects
				(font
					(size 1 1)
					(thickness 0.15)
				)
			)
		)
		(sheetname "/CSI/")
		(sheetfile "csi.kicad_sch")
		(attr smd)
		(fp_rect
			(start -0.925 -0.47)
			(end 0.925 0.47)
			(stroke
				(width 0.05)
				(type default)
			)
			(fill no)
			(layer "F.CrtYd")
		)
		(fp_rect
			(start -0.5 -0.25)
			(end 0.5 0.25)
			(stroke
				(width 0.15)
				(type solid)
			)
			(fill no)
			(layer "F.Fab")
		)
		(fp_text user "License: Apache-2.0"
			(at -0.95 5.169 90)
			(layer "F.Fab")
			(effects
				(font
					(size 0.7 0.7)
					(thickness 0.15)
				)
				(justify right top)
			)
		)
		(fp_text user "${REFERENCE}"
			(at -0.95 3.168 90)
			(layer "F.Fab")
			(effects
				(font
					(size 0.7 0.7)
					(thickness 0.15)
				)
				(justify right top)
			)
		)
		(fp_text user "Author: Antmicro"
			(at -0.95 4.169 90)
			(layer "F.Fab")
			(effects
				(font
					(size 0.7 0.7)
					(thickness 0.15)
				)
				(justify right top)
			)
		)
		(pad "1" smd roundrect
			(at -0.48 0 270)
			(size 0.59 0.64)
			(layers "F.Cu" "F.Mask" "F.Paste")
			(roundrect_rratio 0.25)
			(net 2 "+3V3")
			(pintype "passive")
		)
		(pad "2" smd roundrect
			(at 0.48 0 270)
			(size 0.59 0.64)
			(layers "F.Cu" "F.Mask" "F.Paste")
			(roundrect_rratio 0.25)
			(net 98 "/CSI/CAM_CTRL.CSIA_FLG")
			(pintype "passive")
		)
	)
)
